# T6G (Grand Teton) — schematic netlist excerpt (pin names and nets, part order shuffled) for the footprints in the layout excerpt that follows; sources: Cadence DE-HDL packaged netlist, KiCad conversion of 04192023_DAF0TMB3IC0_F0TG_MB_C_brd_V02_OCP.brd

C107  Q_CAP  1000PF 50V 5% EMPTY  pkg 0402  page 364 : A = PWRGD_P0V9_RETIMER_CPU1_R ; B = GND
C1277  Q_CAP  22UF 16V 20% X6S  pkg C0805  page 145 : A = P12V_E1S_0_R ; B = GND
R1187  Q_RES  1K 1% CHIP  pkg 0402LF  page 83 : A = PVDDCR_CPU0_P1_PMALERT ; B = P3V3_AUX

(kicad_pcb
	(version 20260206)
	(generator "pcbnew")
	(generator_version "10.0")
	(general
		(thickness 1.6)
		(legacy_teardrops no)
	)
	(paper "A4")
	(title_block
		(title "04192023_DAF0TMB3IC0_F0TG_MB_C_brd_V02_OCP.brd")
		(comment 1 "Grand Teton / footprints 706-708 of 8354")
	)
	(layers
		(0 "F.Cu" signal "TOP")
		(4 "In1.Cu" signal "GND")
		(6 "In2.Cu" signal "IN1")
		(8 "In3.Cu" signal "GND1")
		(10 "In4.Cu" signal "IN2")
		(12 "In5.Cu" signal "GND2")
		(14 "In6.Cu" signal "IN3")
		(16 "In7.Cu" signal "GND3")
		(18 "In8.Cu" signal "VCC")
		(20 "In9.Cu" signal "VCC1")
		(22 "In10.Cu" signal "GND4")
		(24 "In11.Cu" signal "IN4")
		(26 "In12.Cu" signal "GND5")
		(28 "In13.Cu" signal "IN5")
		(30 "In14.Cu" signal "GND6")
		(32 "In15.Cu" signal "IN6")
		(34 "In16.Cu" signal "GND7")
		(2 "B.Cu" signal "BOTTOM")
		(9 "F.Adhes" user "F.Adhesive")
		(11 "B.Adhes" user "B.Adhesive")
		(13 "F.Paste" user "Package Geometry/Pastemask Top")
		(15 "B.Paste" user "Package Geometry/Pastemask Bottom")
		(5 "F.SilkS" user "Ref Des/Silkscreen Top")
		(7 "B.SilkS" user "Ref Des/Silkscreen Bottom")
		(1 "F.Mask" user "Board Geometry/Soldermask Top")
		(3 "B.Mask" user "Board Geometry/Soldermask Bottom")
		(17 "Dwgs.User" user "User.Drawings")
		(19 "Cmts.User" user "User.Comments")
		(21 "Eco1.User" user "User.Eco1")
		(23 "Eco2.User" user "User.Eco2")
		(25 "Edge.Cuts" user "Board Geometry/Outline")
		(27 "Margin" user)
		(31 "F.CrtYd" user "Package Geometry/Place Bound Top")
		(29 "B.CrtYd" user "Package Geometry/Place Bound Bottom")
		(35 "F.Fab" user "Ref Des/Assembly Top")
		(33 "B.Fab" user "Ref Des/Assembly Bottom")
	)
	(footprint ""
		(layer "F.Cu")
		(at 185.777124 -96.096074 -90)
		(property "Reference" "R1187"
			(at 0 0 270)
			(layer "F.SilkS")
			(hide yes)
			(effects
				(font
					(size 1.27 1.27)
				)
			)
		)
		(property "Value" ""
			(at 0 0 270)
			(layer "F.Fab")
			(effects
				(font
					(size 1.27 1.27)
				)
			)
		)
		(duplicate_pad_numbers_are_jumpers no)
		(fp_line
			(start -0.7874 0.4064)
			(end -0.7874 -0.4064)
			(stroke
				(width 0.1524)
				(type default)
			)
			(layer "F.SilkS")
		)
		(fp_line
			(start 0.7874 0.4064)
			(end -0.7874 0.4064)
			(stroke
				(width 0.1524)
				(type default)
			)
			(layer "F.SilkS")
		)
		(fp_line
			(start -0.7874 -0.4064)
			(end 0.7874 -0.4064)
			(stroke
				(width 0.1524)
				(type default)
			)
			(layer "F.SilkS")
		)
		(fp_line
			(start 0.7874 -0.4064)
			(end 0.7874 0.4064)
			(stroke
				(width 0.1524)
				(type default)
			)
			(layer "F.SilkS")
		)
		(fp_line
			(start -0.67945 0.3048)
			(end -0.67945 -0.305054)
			(stroke
				(width 0.1)
				(type default)
			)
			(layer "F.Fab")
		)
		(fp_line
			(start -0.12065 0.3048)
			(end -0.67945 0.3048)
			(stroke
				(width 0.1)
				(type default)
			)
			(layer "F.Fab")
		)
		(fp_line
			(start 0.120396 0.3048)
			(end 0.120396 0.2794)
			(stroke
				(width 0.1)
				(type default)
			)
			(layer "F.Fab")
		)
		(fp_line
			(start 0.67945 0.3048)
			(end 0.120396 0.3048)
			(stroke
				(width 0.1)
				(type default)
			)
			(layer "F.Fab")
		)
		(fp_line
			(start -0.12065 0.2794)
			(end -0.12065 0.3048)
			(stroke
				(width 0.1)
				(type default)
			)
			(layer "F.Fab")
		)
		(fp_line
			(start 0.120396 0.2794)
			(end -0.12065 0.2794)
			(stroke
				(width 0.1)
				(type default)
			)
			(layer "F.Fab")
		)
		(fp_line
			(start -0.12065 -0.2794)
			(end 0.12065 -0.2794)
			(stroke
				(width 0.1)
				(type default)
			)
			(layer "F.Fab")
		)
		(fp_line
			(start 0.12065 -0.2794)
			(end 0.12065 -0.3048)
			(stroke
				(width 0.1)
				(type default)
			)
			(layer "F.Fab")
		)
		(fp_line
			(start 0.12065 -0.3048)
			(end 0.67945 -0.3048)
			(stroke
				(width 0.1)
				(type default)
			)
			(layer "F.Fab")
		)
		(fp_line
			(start 0.67945 -0.3048)
			(end 0.67945 0.3048)
			(stroke
				(width 0.1)
				(type default)
			)
			(layer "F.Fab")
		)
		(fp_line
			(start -0.67945 -0.305054)
			(end -0.12065 -0.305054)
			(stroke
				(width 0.1)
				(type default)
			)
			(layer "F.Fab")
		)
		(fp_line
			(start -0.12065 -0.305054)
			(end -0.12065 -0.2794)
			(stroke
				(width 0.1)
				(type default)
			)
			(layer "F.Fab")
		)
		(pad "1" smd circle
			(at -0.40005 0 270)
			(size 0 0)
			(layers "F.Cu" "F.Mask" "F.Paste")
			(net "PVDDCR_CPU0_P1_PMALERT")
		)
		(pad "2" smd circle
			(at 0.40005 0 270)
			(size 0 0)
			(layers "F.Cu" "F.Mask" "F.Paste")
			(net "P3V3_AUX")
		)
	)
	(footprint ""
		(layer "F.Cu")
		(at 243.063268 -44.682918)
		(property "Reference" "C1277"
			(at 0 0 0)
			(layer "F.SilkS")
			(hide yes)
			(effects
				(font
					(size 1.27 1.27)
				)
			)
		)
		(property "Value" ""
			(at 0 0 0)
			(layer "F.Fab")
			(effects
				(font
					(size 1.27 1.27)
				)
			)
		)
		(duplicate_pad_numbers_are_jumpers no)
		(fp_line
			(start -1.524 -0.762)
			(end 1.524 -0.762)
			(stroke
				(width 0.1524)
				(type default)
			)
			(layer "F.SilkS")
		)
		(fp_line
			(start -1.524 0.762)
			(end -1.524 -0.762)
			(stroke
				(width 0.1524)
				(type default)
			)
			(layer "F.SilkS")
		)
		(fp_line
			(start 1.524 -0.762)
			(end 1.524 0.762)
			(stroke
				(width 0.1524)
				(type default)
			)
			(layer "F.SilkS")
		)
		(fp_line
			(start 1.524 0.762)
			(end -1.524 0.762)
			(stroke
				(width 0.1524)
				(type default)
			)
			(layer "F.SilkS")
		)
		(fp_line
			(start -1.1049 -0.724916)
			(end -1.1049 0.724916)
			(stroke
				(width 0.1)
				(type default)
			)
			(layer "F.Fab")
		)
		(fp_line
			(start -1.1049 0.724916)
			(end 1.1049 0.724916)
			(stroke
				(width 0.1)
				(type default)
			)
			(layer "F.Fab")
		)
		(fp_line
			(start 1.1049 -0.724916)
			(end -1.1049 -0.724916)
			(stroke
				(width 0.1)
				(type default)
			)
			(layer "F.Fab")
		)
		(fp_line
			(start 1.1049 0.724916)
			(end 1.1049 -0.724916)
			(stroke
				(width 0.1)
				(type default)
			)
			(layer "F.Fab")
		)
		(pad "1" smd rect
			(at -0.889 0 180)
			(size 1.016 1.27)
			(layers "F.Cu" "F.Mask" "F.Paste")
			(net "P12V_E1S_0_R")
		)
		(pad "2" smd rect
			(at 0.889 0 180)
			(size 1.016 1.27)
			(layers "F.Cu" "F.Mask" "F.Paste")
			(net "GND")
		)
	)
	(footprint ""
		(layer "F.Cu")
		(at 19.508724 -405.868378 -90)
		(property "Reference" "C107"
			(at 0 0 270)
			(layer "F.SilkS")
			(hide yes)
			(effects
				(font
					(size 1.27 1.27)
				)
			)
		)
		(property "Value" ""
			(at 0 0 270)
			(layer "F.Fab")
			(effects
				(font
					(size 1.27 1.27)
				)
			)
		)
		(duplicate_pad_numbers_are_jumpers no)
		(fp_line
			(start -0.7874 0.4064)
			(end -0.7874 -0.4064)
			(stroke
				(width 0.1524)
				(type default)
			)
			(layer "F.SilkS")
		)
		(fp_line
			(start 0.7874 0.4064)
			(end -0.7874 0.4064)
			(stroke
				(width 0.1524)
				(type default)
			)
			(layer "F.SilkS")
		)
		(fp_line
			(start -0.7874 -0.4064)
			(end 0.7874 -0.4064)
			(stroke
				(width 0.1524)
				(type default)
			)
			(layer "F.SilkS")
		)
		(fp_line
			(start 0.7874 -0.4064)
			(end 0.7874 0.4064)
			(stroke
				(width 0.1524)
				(type default)
			)
			(layer "F.SilkS")
		)
		(fp_line
			(start -0.67945 0.3048)
			(end -0.67945 -0.305054)
			(stroke
				(width 0.1)
				(type default)
			)
			(layer "F.Fab")
		)
		(fp_line
			(start -0.12065 0.3048)
			(end -0.67945 0.3048)
			(stroke
				(width 0.1)
				(type default)
			)
			(layer "F.Fab")
		)
		(fp_line
			(start 0.120396 0.3048)
			(end 0.120396 0.2794)
			(stroke
				(width 0.1)
				(type default)
			)
			(layer "F.Fab")
		)
		(fp_line
			(start 0.67945 0.3048)
			(end 0.120396 0.3048)
			(stroke
				(width 0.1)
				(type default)
			)
			(layer "F.Fab")
		)
		(fp_line
			(start -0.12065 0.2794)
			(end -0.12065 0.3048)
			(stroke
				(width 0.1)
				(type default)
			)
			(layer "F.Fab")
		)
		(fp_line
			(start 0.120396 0.2794)
			(end -0.12065 0.2794)
			(stroke
				(width 0.1)
				(type default)
			)
			(layer "F.Fab")
		)
		(fp_line
			(start -0.12065 -0.2794)
			(end 0.12065 -0.2794)
			(stroke
				(width 0.1)
				(type default)
			)
			(layer "F.Fab")
		)
		(fp_line
			(start 0.12065 -0.2794)
			(end 0.12065 -0.3048)
			(stroke
				(width 0.1)
				(type default)
			)
			(layer "F.Fab")
		)
		(fp_line
			(start 0.12065 -0.3048)
			(end 0.67945 -0.3048)
			(stroke
				(width 0.1)
				(type default)
			)
			(layer "F.Fab")
		)
		(fp_line
			(start 0.67945 -0.3048)
			(end 0.67945 0.3048)
			(stroke
				(width 0.1)
				(type default)
			)
			(layer "F.Fab")
		)
		(fp_line
			(start -0.67945 -0.305054)
			(end -0.12065 -0.305054)
			(stroke
				(width 0.1)
				(type default)
			)
			(layer "F.Fab")
		)
		(fp_line
			(start -0.12065 -0.305054)
			(end -0.12065 -0.2794)
			(stroke
				(width 0.1)
				(type default)
			)
			(layer "F.Fab")
		)
		(pad "1" smd circle
			(at -0.40005 0 270)
			(size 0 0)
			(layers "F.Cu" "F.Mask" "F.Paste")
			(net "PWRGD_P0V9_RETIMER_CPU1_R")
		)
		(pad "2" smd circle
			(at 0.40005 0 270)
			(size 0 0)
			(layers "F.Cu" "F.Mask" "F.Paste")
			(net "GND")
		)
	)
)
